# TIMECARD (Time Appliance Project (Time Card)) — schematic netlist excerpt (pin names and nets, part order shuffled) for the footprints in the layout excerpt that follows; sources: Cadence DE-HDL packaged netlist, KiCad conversion of R4006-B0001-02_R01.brd

R181  RESISTOR  0OHM -  pkg SMC_0402R_H016  page 30 : \1\ = XP1R2V_PG_R ; \2\ = XP1R2V_FPGA_PG

(kicad_pcb
	(version 20260206)
	(generator "pcbnew")
	(generator_version "10.0")
	(general
		(thickness 1.6)
		(legacy_teardrops no)
	)
	(paper "A4")
	(title_block
		(title "timecard-production-celestica-r4006 — R4006-B0001-02_R01.brd")
		(comment 1 "Time Appliance Project (Time Card) / footprints 547-547 of 1113")
	)
	(layers
		(0 "F.Cu" signal "TOP")
		(4 "In1.Cu" signal "L02_GND1")
		(6 "In2.Cu" signal "L03_SIG1")
		(8 "In3.Cu" signal "L04_GND2")
		(10 "In4.Cu" signal "L05_VCC1")
		(12 "In5.Cu" signal "L06_VCC2")
		(14 "In6.Cu" signal "L07_GND3")
		(16 "In7.Cu" signal "L08_SIG2")
		(18 "In8.Cu" signal "L09_GND4")
		(2 "B.Cu" signal "BOTTOM")
		(9 "F.Adhes" user "F.Adhesive")
		(11 "B.Adhes" user "B.Adhesive")
		(13 "F.Paste" user "Package Geometry/Pastemask Top")
		(15 "B.Paste" user "Package Geometry/Pastemask Bottom")
		(5 "F.SilkS" user "Ref Des/Silkscreen Top")
		(7 "B.SilkS" user "Ref Des/Silkscreen Bottom")
		(1 "F.Mask" user "Board Geometry/Soldermask Top")
		(3 "B.Mask" user "Board Geometry/Soldermask Bottom")
		(17 "Dwgs.User" user "User.Drawings")
		(19 "Cmts.User" user "User.Comments")
		(21 "Eco1.User" user "User.Eco1")
		(23 "Eco2.User" user "User.Eco2")
		(25 "Edge.Cuts" user "Board Geometry/Outline")
		(27 "Margin" user)
		(31 "F.CrtYd" user "Package Geometry/Place Bound Top")
		(29 "B.CrtYd" user "Package Geometry/Place Bound Bottom")
		(35 "F.Fab" user "Ref Des/Assembly Top")
		(33 "B.Fab" user "Ref Des/Assembly Bottom")
	)
	(footprint ""
		(layer "F.Cu")
		(at 100.2538 -69.215)
		(property "Reference" "R181"
			(at 2.8702 -0.08763 0)
			(unlocked yes)
			(layer "F.SilkS")
			(effects
				(font
					(size 0.7874 0.5842)
					(thickness 0.1524)
				)
			)
		)
		(property "Value" "VAL*"
			(at 0.02032 2.13233 0)
			(unlocked yes)
			(layer "F.Fab")
			(hide yes)
			(effects
				(font
					(size 0.7874 0.5842)
					(thickness 0.1524)
				)
			)
		)
		(property "Tolerance" "TOL*"
			(at 0.044704 3.05435 0)
			(unlocked yes)
			(layer "Cmts.User")
			(hide yes)
			(effects
				(font
					(size 0.7874 0.5842)
					(thickness 0.1524)
				)
			)
		)
		(property "User Part Number" "PARTNUM*"
			(at 0.02032 4.024884 0)
			(unlocked yes)
			(layer "Cmts.User")
			(hide yes)
			(effects
				(font
					(size 0.7874 0.5842)
					(thickness 0.1524)
				)
			)
		)
		(property "Device Type" "RESISTOR-G155-100R0-J0,0OHM,-"
			(at 0.008382 1.210564 0)
			(unlocked yes)
			(layer "F.Fab")
			(hide yes)
			(effects
				(font
					(size 0.7874 0.5842)
					(thickness 0.1524)
				)
			)
		)
		(duplicate_pad_numbers_are_jumpers no)
		(fp_line
			(start -1.143 -0.5588)
			(end -1.143 0.5588)
			(stroke
				(width 0.1)
				(type default)
			)
			(layer "F.SilkS")
		)
		(fp_line
			(start -1.143 0.5588)
			(end 1.143 0.5588)
			(stroke
				(width 0.1)
				(type default)
			)
			(layer "F.SilkS")
		)
		(fp_line
			(start 1.143 -0.5588)
			(end -1.143 -0.5588)
			(stroke
				(width 0.1)
				(type default)
			)
			(layer "F.SilkS")
		)
		(fp_line
			(start 1.143 0.5588)
			(end 1.143 -0.5588)
			(stroke
				(width 0.1)
				(type default)
			)
			(layer "F.SilkS")
		)
		(fp_rect
			(start -1.143 -0.5588)
			(end 1.143 0.5588)
			(stroke
				(width 0)
				(type default)
			)
			(fill no)
			(layer "F.CrtYd")
		)
		(fp_line
			(start -0.508 -0.3048)
			(end -0.508 0.3048)
			(stroke
				(width 0.1)
				(type default)
			)
			(layer "F.Fab")
		)
		(fp_line
			(start -0.508 0.3048)
			(end 0.508 0.3048)
			(stroke
				(width 0.1)
				(type default)
			)
			(layer "F.Fab")
		)
		(fp_line
			(start 0.508 -0.3048)
			(end -0.508 -0.3048)
			(stroke
				(width 0.1)
				(type default)
			)
			(layer "F.Fab")
		)
		(fp_line
			(start 0.508 0.3048)
			(end 0.508 -0.3048)
			(stroke
				(width 0.1)
				(type default)
			)
			(layer "F.Fab")
		)
		(pad "1" smd rect
			(at -0.5334 0)
			(size 0.7112 0.6096)
			(layers "F.Cu" "F.Mask" "F.Paste")
			(net "XP1R2V_PG_R")
		)
		(pad "2" smd rect
			(at 0.5334 0)
			(size 0.7112 0.6096)
			(layers "F.Cu" "F.Mask" "F.Paste")
			(net "XP1R2V_FPGA_PG")
		)
		(zone
			(layer "F.Cu")
			(hatch none 0.5)
			(connect_pads
				(clearance 0)
			)
			(min_thickness 0.25)
			(keepout
				(tracks allowed)
				(vias not_allowed)
				(pads allowed)
				(copperpour not_allowed)
				(footprints allowed)
			)
			(placement
				(enabled no)
				(sheetname "")
			)
			(fill
				(thermal_gap 0.5)
				(thermal_bridge_width 0.5)
				(island_removal_mode 0)
			)
			(polygon
				(pts
					(xy 100.1776 -69.5198) (xy 100.1776 -68.9102) (xy 100.33 -68.9102) (xy 100.33 -69.5198)
				)
			)
		)
	)
)
